(kicad_pcb
	(version 20260206)
	(generator "pcbnew")
	(generator_version "10.0")
	(general
		(thickness 1.6)
		(legacy_teardrops no)
	)
	(paper "A4")
	(title_block
		(title "04192023_DAF0TMB3IC0_F0TG_MB_C_brd_V02_OCP.brd")
		(comment 1 "Grand Teton / footprints 1287-1293 of 8354")
	)
	(layers
		(0 "F.Cu" signal "TOP")
		(4 "In1.Cu" signal "GND")
		(6 "In2.Cu" signal "IN1")
		(8 "In3.Cu" signal "GND1")
		(10 "In4.Cu" signal "IN2")
		(12 "In5.Cu" signal "GND2")
		(14 "In6.Cu" signal "IN3")
		(16 "In7.Cu" signal "GND3")
		(18 "In8.Cu" signal "VCC")
		(20 "In9.Cu" signal "VCC1")
		(22 "In10.Cu" signal "GND4")
		(24 "In11.Cu" signal "IN4")
		(26 "In12.Cu" signal "GND5")
		(28 "In13.Cu" signal "IN5")
		(30 "In14.Cu" signal "GND6")
		(32 "In15.Cu" signal "IN6")
		(34 "In16.Cu" signal "GND7")
		(2 "B.Cu" signal "BOTTOM")
		(9 "F.Adhes" user "F.Adhesive")
		(11 "B.Adhes" user "B.Adhesive")
		(13 "F.Paste" user "Package Geometry/Pastemask Top")
		(15 "B.Paste" user "Package Geometry/Pastemask Bottom")
		(5 "F.SilkS" user "Ref Des/Silkscreen Top")
		(7 "B.SilkS" user "Ref Des/Silkscreen Bottom")
		(1 "F.Mask" user "Board Geometry/Soldermask Top")
		(3 "B.Mask" user "Board Geometry/Soldermask Bottom")
		(17 "Dwgs.User" user "User.Drawings")
		(19 "Cmts.User" user "User.Comments")
		(21 "Eco1.User" user "User.Eco1")
		(23 "Eco2.User" user "User.Eco2")
		(25 "Edge.Cuts" user "Board Geometry/Outline")
		(27 "Margin" user)
		(31 "F.CrtYd" user "Package Geometry/Place Bound Top")
		(29 "B.CrtYd" user "Package Geometry/Place Bound Bottom")
		(35 "F.Fab" user "Ref Des/Assembly Top")
		(33 "B.Fab" user "Ref Des/Assembly Bottom")
	)
	(footprint ""
		(layer "F.Cu")
		(at 312.443876 -70.098412 90)
		(property "Reference" "D88"
			(at -3.934714 -0.691642 90)
			(unlocked yes)
			(layer "F.SilkS")
			(effects
				(font
					(size 0.7874 0.5842)
					(thickness 0.1524)
				)
				(justify left)
			)
		)
		(property "Value" ""
			(at 0 0 90)
			(layer "F.Fab")
			(effects
				(font
					(size 1.27 1.27)
				)
			)
		)
		(duplicate_pad_numbers_are_jumpers no)
		(fp_line
			(start 1.16078 -0.4826)
			(end 1.16078 0.4826)
			(stroke
				(width 0.1524)
				(type default)
			)
			(layer "F.SilkS")
		)
		(fp_line
			(start 1.03378 -0.4826)
			(end 1.03378 0.4826)
			(stroke
				(width 0.1524)
				(type default)
			)
			(layer "F.SilkS")
		)
		(fp_line
			(start 0.90678 -0.4826)
			(end 0.90678 0.4826)
			(stroke
				(width 0.1524)
				(type default)
			)
			(layer "F.SilkS")
		)
		(fp_line
			(start -0.64008 -0.4826)
			(end 1.16078 -0.4826)
			(stroke
				(width 0.1524)
				(type default)
			)
			(layer "F.SilkS")
		)
		(fp_line
			(start -0.79248 -0.4826)
			(end 1.03378 -0.4826)
			(stroke
				(width 0.1524)
				(type default)
			)
			(layer "F.SilkS")
		)
		(fp_line
			(start -0.89408 -0.4826)
			(end 0.90678 -0.4826)
			(stroke
				(width 0.1524)
				(type default)
			)
			(layer "F.SilkS")
		)
		(fp_line
			(start 1.16078 0.4826)
			(end -0.64008 0.4826)
			(stroke
				(width 0.1524)
				(type default)
			)
			(layer "F.SilkS")
		)
		(fp_line
			(start 1.03378 0.4826)
			(end -0.79248 0.4826)
			(stroke
				(width 0.1524)
				(type default)
			)
			(layer "F.SilkS")
		)
		(fp_line
			(start 0.90678 0.4826)
			(end -0.90678 0.4826)
			(stroke
				(width 0.1524)
				(type default)
			)
			(layer "F.SilkS")
		)
		(fp_line
			(start -0.90678 0.4826)
			(end -0.90678 -0.4699)
			(stroke
				(width 0.1524)
				(type default)
			)
			(layer "F.SilkS")
		)
		(fp_line
			(start 0.499872 -0.249936)
			(end 0.499872 0.249936)
			(stroke
				(width 0.1)
				(type default)
			)
			(layer "F.Fab")
		)
		(fp_line
			(start -0.499872 -0.249936)
			(end 0.499872 -0.249936)
			(stroke
				(width 0.1)
				(type default)
			)
			(layer "F.Fab")
		)
		(fp_line
			(start 0.499872 0.249936)
			(end -0.499872 0.249936)
			(stroke
				(width 0.1)
				(type default)
			)
			(layer "F.Fab")
		)
		(fp_line
			(start -0.499872 0.249936)
			(end -0.499872 -0.249936)
			(stroke
				(width 0.1)
				(type default)
			)
			(layer "F.Fab")
		)
		(pad "A" smd rect
			(at -0.47498 0 90)
			(size 0.6096 0.7112)
			(layers "F.Cu" "F.Mask" "F.Paste")
			(net "LED_PWRGD_SYS_PWROK_R")
		)
		(pad "C" smd rect
			(at 0.47498 0 90)
			(size 0.6096 0.7112)
			(layers "F.Cu" "F.Mask" "F.Paste")
			(net "LED_PWRGD_SYS_PWROK_R_D")
		)
	)
	(footprint ""
		(layer "F.Cu")
		(at 156.322522 -191.361314 -90)
		(property "Reference" "R3195"
			(at 0 0 270)
			(layer "F.SilkS")
			(hide yes)
			(effects
				(font
					(size 1.27 1.27)
				)
			)
		)
		(property "Value" ""
			(at 0 0 270)
			(layer "F.Fab")
			(effects
				(font
					(size 1.27 1.27)
				)
			)
		)
		(duplicate_pad_numbers_are_jumpers no)
		(fp_line
			(start 0.353314 0.4064)
			(end -0.383286 0.4064)
			(stroke
				(width 0.1524)
				(type default)
			)
			(layer "F.SilkS")
		)
		(fp_line
			(start -0.7874 -0.014478)
			(end -0.7874 -0.4064)
			(stroke
				(width 0.1524)
				(type default)
			)
			(layer "F.SilkS")
		)
		(fp_line
			(start -0.7874 -0.4064)
			(end 0.7874 -0.4064)
			(stroke
				(width 0.1524)
				(type default)
			)
			(layer "F.SilkS")
		)
		(fp_line
			(start 0.7874 -0.4064)
			(end 0.7874 -0.014478)
			(stroke
				(width 0.1524)
				(type default)
			)
			(layer "F.SilkS")
		)
		(fp_line
			(start -0.67945 0.3048)
			(end -0.67945 -0.305054)
			(stroke
				(width 0.1)
				(type default)
			)
			(layer "F.Fab")
		)
		(fp_line
			(start -0.12065 0.3048)
			(end -0.67945 0.3048)
			(stroke
				(width 0.1)
				(type default)
			)
			(layer "F.Fab")
		)
		(fp_line
			(start 0.120396 0.3048)
			(end 0.120396 0.2794)
			(stroke
				(width 0.1)
				(type default)
			)
			(layer "F.Fab")
		)
		(fp_line
			(start 0.67945 0.3048)
			(end 0.120396 0.3048)
			(stroke
				(width 0.1)
				(type default)
			)
			(layer "F.Fab")
		)
		(fp_line
			(start -0.12065 0.2794)
			(end -0.12065 0.3048)
			(stroke
				(width 0.1)
				(type default)
			)
			(layer "F.Fab")
		)
		(fp_line
			(start 0.120396 0.2794)
			(end -0.12065 0.2794)
			(stroke
				(width 0.1)
				(type default)
			)
			(layer "F.Fab")
		)
		(fp_line
			(start -0.12065 -0.2794)
			(end 0.12065 -0.2794)
			(stroke
				(width 0.1)
				(type default)
			)
			(layer "F.Fab")
		)
		(fp_line
			(start 0.12065 -0.2794)
			(end 0.12065 -0.3048)
			(stroke
				(width 0.1)
				(type default)
			)
			(layer "F.Fab")
		)
		(fp_line
			(start 0.12065 -0.3048)
			(end 0.67945 -0.3048)
			(stroke
				(width 0.1)
				(type default)
			)
			(layer "F.Fab")
		)
		(fp_line
			(start 0.67945 -0.3048)
			(end 0.67945 0.3048)
			(stroke
				(width 0.1)
				(type default)
			)
			(layer "F.Fab")
		)
		(fp_line
			(start -0.67945 -0.305054)
			(end -0.12065 -0.305054)
			(stroke
				(width 0.1)
				(type default)
			)
			(layer "F.Fab")
		)
		(fp_line
			(start -0.12065 -0.305054)
			(end -0.12065 -0.2794)
			(stroke
				(width 0.1)
				(type default)
			)
			(layer "F.Fab")
		)
		(pad "1" smd circle
			(at -0.40005 0 270)
			(size 0 0)
			(layers "F.Cu" "F.Mask" "F.Paste")
			(net "CLK_100M_CPU1_CLK02_R_DN")
		)
		(pad "2" smd circle
			(at 0.40005 0 270)
			(size 0 0)
			(layers "F.Cu" "F.Mask" "F.Paste")
			(net "CLK_100M_CPU1_CLK02_DN")
		)
	)
	(footprint ""
		(layer "F.Cu")
		(at 100.382832 -47.049944)
		(property "Reference" "H32"
			(at -1.7272 -4.511548 0)
			(unlocked yes)
			(layer "B.SilkS")
			(effects
				(font
					(size 0.7874 0.5842)
					(thickness 0.1524)
				)
				(justify left mirror)
			)
		)
		(property "Value" ""
			(at 0 0 0)
			(layer "F.Fab")
			(effects
				(font
					(size 1.27 1.27)
				)
			)
		)
		(duplicate_pad_numbers_are_jumpers no)
		(pad "1" thru_hole circle
			(at 0 0)
			(size 4.5212 4.5212)
			(drill 3.81)
			(layers "*.Cu" "*.Mask")
			(remove_unused_layers no)
			(net "GND")
			(clearance -0.1016)
			(padstack
				(mode front_inner_back)
				(layer "Inner"
					(shape circle)
					(size 5.6134 5.6134)
					(clearance -0.6477)
				)
				(layer "B.Cu"
					(shape circle)
					(size 8.001 8.001)
					(clearance -1.8415)
				)
			)
		)
	)
	(footprint ""
		(layer "F.Cu")
		(at 180.395118 -365.058452 90)
		(property "Reference" "PC511"
			(at 0 0 90)
			(layer "F.SilkS")
			(hide yes)
			(effects
				(font
					(size 1.27 1.27)
				)
			)
		)
		(property "Value" ""
			(at 0 0 90)
			(layer "F.Fab")
			(effects
				(font
					(size 1.27 1.27)
				)
			)
		)
		(duplicate_pad_numbers_are_jumpers no)
		(fp_line
			(start 0.7874 -0.4064)
			(end 0.7874 0.4064)
			(stroke
				(width 0.1524)
				(type default)
			)
			(layer "F.SilkS")
		)
		(fp_line
			(start -0.7874 -0.4064)
			(end 0.7874 -0.4064)
			(stroke
				(width 0.1524)
				(type default)
			)
			(layer "F.SilkS")
		)
		(fp_line
			(start 0.7874 0.4064)
			(end -0.7874 0.4064)
			(stroke
				(width 0.1524)
				(type default)
			)
			(layer "F.SilkS")
		)
		(fp_line
			(start -0.7874 0.4064)
			(end -0.7874 -0.4064)
			(stroke
				(width 0.1524)
				(type default)
			)
			(layer "F.SilkS")
		)
		(fp_line
			(start -0.12065 -0.305054)
			(end -0.12065 -0.2794)
			(stroke
				(width 0.1)
				(type default)
			)
			(layer "F.Fab")
		)
		(fp_line
			(start -0.67945 -0.305054)
			(end -0.12065 -0.305054)
			(stroke
				(width 0.1)
				(type default)
			)
			(layer "F.Fab")
		)
		(fp_line
			(start 0.67945 -0.3048)
			(end 0.67945 0.3048)
			(stroke
				(width 0.1)
				(type default)
			)
			(layer "F.Fab")
		)
		(fp_line
			(start 0.12065 -0.3048)
			(end 0.67945 -0.3048)
			(stroke
				(width 0.1)
				(type default)
			)
			(layer "F.Fab")
		)
		(fp_line
			(start 0.12065 -0.2794)
			(end 0.12065 -0.3048)
			(stroke
				(width 0.1)
				(type default)
			)
			(layer "F.Fab")
		)
		(fp_line
			(start -0.12065 -0.2794)
			(end 0.12065 -0.2794)
			(stroke
				(width 0.1)
				(type default)
			)
			(layer "F.Fab")
		)
		(fp_line
			(start 0.120396 0.2794)
			(end -0.12065 0.2794)
			(stroke
				(width 0.1)
				(type default)
			)
			(layer "F.Fab")
		)
		(fp_line
			(start -0.12065 0.2794)
			(end -0.12065 0.3048)
			(stroke
				(width 0.1)
				(type default)
			)
			(layer "F.Fab")
		)
		(fp_line
			(start 0.67945 0.3048)
			(end 0.120396 0.3048)
			(stroke
				(width 0.1)
				(type default)
			)
			(layer "F.Fab")
		)
		(fp_line
			(start 0.120396 0.3048)
			(end 0.120396 0.2794)
			(stroke
				(width 0.1)
				(type default)
			)
			(layer "F.Fab")
		)
		(fp_line
			(start -0.12065 0.3048)
			(end -0.67945 0.3048)
			(stroke
				(width 0.1)
				(type default)
			)
			(layer "F.Fab")
		)
		(fp_line
			(start -0.67945 0.3048)
			(end -0.67945 -0.305054)
			(stroke
				(width 0.1)
				(type default)
			)
			(layer "F.Fab")
		)
		(pad "1" smd circle
			(at -0.40005 0 90)
			(size 0 0)
			(layers "F.Cu" "F.Mask" "F.Paste")
			(net "P12V_AUX")
		)
		(pad "2" smd circle
			(at 0.40005 0 90)
			(size 0 0)
			(layers "F.Cu" "F.Mask" "F.Paste")
			(net "GND")
		)
	)
	(footprint ""
		(layer "F.Cu")
		(at 290.603178 -423.434764 90)
		(property "Reference" "R4518"
			(at 0 0 90)
			(layer "F.SilkS")
			(hide yes)
			(effects
				(font
					(size 1.27 1.27)
				)
			)
		)
		(property "Value" ""
			(at 0 0 90)
			(layer "F.Fab")
			(effects
				(font
					(size 1.27 1.27)
				)
			)
		)
		(duplicate_pad_numbers_are_jumpers no)
		(fp_line
			(start 0.7874 -0.4064)
			(end 0.7874 0.4064)
			(stroke
				(width 0.1524)
				(type default)
			)
			(layer "F.SilkS")
		)
		(fp_line
			(start -0.7874 -0.4064)
			(end 0.7874 -0.4064)
			(stroke
				(width 0.1524)
				(type default)
			)
			(layer "F.SilkS")
		)
		(fp_line
			(start 0.7874 0.4064)
			(end -0.7874 0.4064)
			(stroke
				(width 0.1524)
				(type default)
			)
			(layer "F.SilkS")
		)
		(fp_line
			(start -0.7874 0.4064)
			(end -0.7874 -0.4064)
			(stroke
				(width 0.1524)
				(type default)
			)
			(layer "F.SilkS")
		)
		(fp_line
			(start -0.12065 -0.305054)
			(end -0.12065 -0.2794)
			(stroke
				(width 0.1)
				(type default)
			)
			(layer "F.Fab")
		)
		(fp_line
			(start -0.67945 -0.305054)
			(end -0.12065 -0.305054)
			(stroke
				(width 0.1)
				(type default)
			)
			(layer "F.Fab")
		)
		(fp_line
			(start 0.67945 -0.3048)
			(end 0.67945 0.3048)
			(stroke
				(width 0.1)
				(type default)
			)
			(layer "F.Fab")
		)
		(fp_line
			(start 0.12065 -0.3048)
			(end 0.67945 -0.3048)
			(stroke
				(width 0.1)
				(type default)
			)
			(layer "F.Fab")
		)
		(fp_line
			(start 0.12065 -0.2794)
			(end 0.12065 -0.3048)
			(stroke
				(width 0.1)
				(type default)
			)
			(layer "F.Fab")
		)
		(fp_line
			(start -0.12065 -0.2794)
			(end 0.12065 -0.2794)
			(stroke
				(width 0.1)
				(type default)
			)
			(layer "F.Fab")
		)
		(fp_line
			(start 0.120396 0.2794)
			(end -0.12065 0.2794)
			(stroke
				(width 0.1)
				(type default)
			)
			(layer "F.Fab")
		)
		(fp_line
			(start -0.12065 0.2794)
			(end -0.12065 0.3048)
			(stroke
				(width 0.1)
				(type default)
			)
			(layer "F.Fab")
		)
		(fp_line
			(start 0.67945 0.3048)
			(end 0.120396 0.3048)
			(stroke
				(width 0.1)
				(type default)
			)
			(layer "F.Fab")
		)
		(fp_line
			(start 0.120396 0.3048)
			(end 0.120396 0.2794)
			(stroke
				(width 0.1)
				(type default)
			)
			(layer "F.Fab")
		)
		(fp_line
			(start -0.12065 0.3048)
			(end -0.67945 0.3048)
			(stroke
				(width 0.1)
				(type default)
			)
			(layer "F.Fab")
		)
		(fp_line
			(start -0.67945 0.3048)
			(end -0.67945 -0.305054)
			(stroke
				(width 0.1)
				(type default)
			)
			(layer "F.Fab")
		)
		(pad "1" smd circle
			(at -0.40005 0 90)
			(size 0 0)
			(layers "F.Cu" "F.Mask" "F.Paste")
			(net "FM_9ZXL045_P0_2_OE_N")
		)
		(pad "2" smd circle
			(at 0.40005 0 90)
			(size 0 0)
			(layers "F.Cu" "F.Mask" "F.Paste")
			(net "GND")
		)
	)
	(footprint ""
		(layer "F.Cu")
		(at 313.872626 -416.899344 -90)
		(property "Reference" "C6507"
			(at 0 0 270)
			(layer "F.SilkS")
			(hide yes)
			(effects
				(font
					(size 1.27 1.27)
				)
			)
		)
		(property "Value" ""
			(at 0 0 270)
			(layer "F.Fab")
			(effects
				(font
					(size 1.27 1.27)
				)
			)
		)
		(duplicate_pad_numbers_are_jumpers no)
		(fp_line
			(start -0.299974 0.150114)
			(end -0.299974 -0.150114)
			(stroke
				(width 0.1)
				(type default)
			)
			(layer "F.Fab")
		)
		(fp_line
			(start 0.299974 0.150114)
			(end -0.299974 0.150114)
			(stroke
				(width 0.1)
				(type default)
			)
			(layer "F.Fab")
		)
		(fp_line
			(start -0.299974 -0.150114)
			(end 0.299974 -0.150114)
			(stroke
				(width 0.1)
				(type default)
			)
			(layer "F.Fab")
		)
		(fp_line
			(start 0.299974 -0.150114)
			(end 0.299974 0.150114)
			(stroke
				(width 0.1)
				(type default)
			)
			(layer "F.Fab")
		)
		(pad "1" smd rect
			(at -0.2667 0 270)
			(size 0.3048 0.381)
			(layers "F.Cu" "F.Mask" "F.Paste")
			(net "P5E_CPU0_P0_TX_BUF_C_DP<3>")
		)
		(pad "2" smd rect
			(at 0.2667 0 270)
			(size 0.3048 0.381)
			(layers "F.Cu" "F.Mask" "F.Paste")
			(net "P5E_CPU0_P0_TX_BUF_DP<3>")
		)
	)
	(footprint ""
		(layer "F.Cu")
		(at 372.937278 -146.552158 180)
		(property "Reference" "R8287"
			(at 0 0 180)
			(layer "F.SilkS")
			(hide yes)
			(effects
				(font
					(size 1.27 1.27)
				)
			)
		)
		(property "Value" ""
			(at 0 0 180)
			(layer "F.Fab")
			(effects
				(font
					(size 1.27 1.27)
				)
			)
		)
		(duplicate_pad_numbers_are_jumpers no)
		(fp_line
			(start 0.7874 0.4064)
			(end -0.7874 0.4064)
			(stroke
				(width 0.1524)
				(type default)
			)
			(layer "F.SilkS")
		)
		(fp_line
			(start 0.7874 -0.4064)
			(end 0.7874 0.4064)
			(stroke
				(width 0.1524)
				(type default)
			)
			(layer "F.SilkS")
		)
		(fp_line
			(start -0.7874 0.4064)
			(end -0.7874 -0.4064)
			(stroke
				(width 0.1524)
				(type default)
			)
			(layer "F.SilkS")
		)
		(fp_line
			(start -0.7874 -0.4064)
			(end 0.7874 -0.4064)
			(stroke
				(width 0.1524)
				(type default)
			)
			(layer "F.SilkS")
		)
		(fp_line
			(start 0.67945 0.3048)
			(end 0.120396 0.3048)
			(stroke
				(width 0.1)
				(type default)
			)
			(layer "F.Fab")
		)
		(fp_line
			(start 0.67945 -0.3048)
			(end 0.67945 0.3048)
			(stroke
				(width 0.1)
				(type default)
			)
			(layer "F.Fab")
		)
		(fp_line
			(start 0.12065 -0.2794)
			(end 0.12065 -0.3048)
			(stroke
				(width 0.1)
				(type default)
			)
			(layer "F.Fab")
		)
		(fp_line
			(start 0.12065 -0.3048)
			(end 0.67945 -0.3048)
			(stroke
				(width 0.1)
				(type default)
			)
			(layer "F.Fab")
		)
		(fp_line
			(start 0.120396 0.3048)
			(end 0.120396 0.2794)
			(stroke
				(width 0.1)
				(type default)
			)
			(layer "F.Fab")
		)
		(fp_line
			(start 0.120396 0.2794)
			(end -0.12065 0.2794)
			(stroke
				(width 0.1)
				(type default)
			)
			(layer "F.Fab")
		)
		(fp_line
			(start -0.12065 0.3048)
			(end -0.67945 0.3048)
			(stroke
				(width 0.1)
				(type default)
			)
			(layer "F.Fab")
		)
		(fp_line
			(start -0.12065 0.2794)
			(end -0.12065 0.3048)
			(stroke
				(width 0.1)
				(type default)
			)
			(layer "F.Fab")
		)
		(fp_line
			(start -0.12065 -0.2794)
			(end 0.12065 -0.2794)
			(stroke
				(width 0.1)
				(type default)
			)
			(layer "F.Fab")
		)
		(fp_line
			(start -0.12065 -0.305054)
			(end -0.12065 -0.2794)
			(stroke
				(width 0.1)
				(type default)
			)
			(layer "F.Fab")
		)
		(fp_line
			(start -0.67945 0.3048)
			(end -0.67945 -0.305054)
			(stroke
				(width 0.1)
				(type default)
			)
			(layer "F.Fab")
		)
		(fp_line
			(start -0.67945 -0.305054)
			(end -0.12065 -0.305054)
			(stroke
				(width 0.1)
				(type default)
			)
			(layer "F.Fab")
		)
		(pad "1" smd circle
			(at -0.40005 0 180)
			(size 0 0)
			(layers "F.Cu" "F.Mask" "F.Paste")
			(net "PVDD18_S5_P0")
		)
		(pad "2" smd circle
			(at 0.40005 0 180)
			(size 0 0)
			(layers "F.Cu" "F.Mask" "F.Paste")
			(net "SVID_PVDDCR_CPU0_P0_SVTO")
		)
	)
)
